# Lightning M2 Carrier BOM.xlsx — BOM cost (bom)
| Wiwynn |  |  | BOM |  |  |  |  |  |  |  |  |  |  |  |  |  |  |  |  |  |  |  |  |  |  |  |  |  |  |  |
| Model: | Lightning HU-230L |  |  |  |  |  |  |  |  |  |  |  |  |  |  |  |  |  |  |  |  |  |  |  |  |  |  |  |  |  |
| Project Code.: BPD00Q010001 |  |  | Version:1.0 |  |  |  |  |  |  |  |  |  |  |  |  |  |  |  |  |  |  |  |  |  |  |  |  |  |  |  |
| Vendor: |  |  | 2016/08/04 |  |  |  |  |  |  |  |  | PVT |  |  |  |  |  |  |  |  |  |  |  |  |  |  |  |  |  |  |
| No | Level | Wistron Part Number | Description | Part Name | Picture | Q'ty for lower level | Unit Q'ty per system | Lyra Lite System Q'ty | Material/Finish | Type | Suppier | Tooling |  |  |  |  | NCT 300 sets |  | Breakeven  point per system | Hybrid | Remark |  |  |  |  |  |  |  |  |  |
|  |  |  |  |  |  |  |  |  |  | Assy/Metal/ Plastic/Purchase/Cable |  | New Tooling fee (USD) | Tooling modification fee (USD) | Existing tooling fee (USD) | U/P - tooling (USD) | tooled parts price per system (USD) | U/P - NCT (USD) | NCT parts price per system (USD) |  |  |  | 2D Drawing Release Day | Drawing Version | PDM | Design Frozen | PCC | Vendor | 發布 | Checking or completely | Checking or completely |
|  | 0 | DC.xxxxx.xxx |  |  |  | 1 | 1 | 1 |  |  |  |  |  |  |  |  |  |  |  |  |  |  |  |  |  | V |  |  |  |  |
|  |  | B60.00Q18.0001 | ASSY M2 METAL CARRIER LIGHTNING |  |  |  |  |  |  |  |  |  |  |  |  |  |  |  |  |  |  |  |  |  |  |  |  |  |  |  |
| 1 | 1 | B30.00Q03.0001 | CAS M2 CARRIER PVT LIGHTNING | 13-000412_ENCLOSURE_M2_V1 |  | 1 | 1 |  | ADC12 | Metal |  |  |  |  |  |  |  |  |  |  |  |  |  |  |  |  |  |  |  |  |
| 2 | 1 | B60.00Q1D.0001 | ASSY M2 LEFT HEATSINK PVT LIGHTNING | AVA TOP HS CONCEPT ASSY |  | 1 | 1 |  |  | ASSY |  |  |  |  |  |  |  |  |  |  |  |  |  |  |  |  |  |  |  |  |
| 3 | 2 | B33.00Q0K.0001 | BRKT M2 LEFT HEATSINK PVT LIGHTNING | HEAT SINK M.2 LEFT SIDE |  | 1 | 1 |  | ADC12 | Metal |  |  |  |  |  |  |  |  |  |  |  |  |  |  |  |  |  |  |  |  |
| 4 | 2 | B42.00Q0O.0001 | LATCH M2 HEATSINK PVT LIGHTNING | AVA TOP HS LATCH CONCEPT2 |  | 1 | 1 |  | JPSeco NFrPP325m | Plastic |  |  |  |  |  |  |  |  |  |  |  |  |  |  |  |  |  |  |  |  |
| 5 | 2 | B34.00Q0C.0001 | SPG M2 LATCH LIGHTNING | AVA HS SPRING CONCEPT2 |  | 1 | 1 |  | Spring | Purchase |  |  |  |  |  |  |  |  |  |  |  |  |  |  |  |  |  |  |  |  |
| 6 | 1 | B60.00Q1E.0001 | ASSY M2 RIGHT HEATSINK PVT LIGHTNING | AVA TOP HS RIGHT CONCEPT ASSY |  | 1 | 1 |  |  | Assy |  |  |  |  |  |  |  |  |  |  |  |  |  |  |  |  |  |  |  |  |
| 7 | 2 | B33.00Q0L.0001 | BRKT M2 RIGHT HEATSINK PVT LIGHTNING | HEAT SINK M.2 RIGHT SIDE |  | 1 | 1 |  | ADC12 | Metal |  |  |  |  |  |  |  |  |  |  |  |  |  |  |  |  |  |  |  |  |
| 8 | 2 | B42.00Q0O.0001 | LATCH M2 HEATSINK PVT LIGHTNING | AVA TOP HS LATCH CONCEPT2 |  | 1 | 1 |  | JPSeco NFrPP325m | Plastic |  |  |  |  |  |  |  |  |  |  |  |  |  |  |  |  |  |  |  |  |
| 9 | 2 | B34.00Q0C.0001 | SPG M2 LATCH LIGHTNING | AVA TOP HS LATCH CONCEPT2 |  | 1 | 1 |  | Spring | Purchase |  |  |  |  |  |  |  |  |  |  |  |  |  |  |  |  |  |  |  |  |
| 10 | 1 | B60.00Q1G.0001 | ASSY M2 COVER PVT LIGHTNING | 13-000411 COVER V1 ASM |  | 1 | 1 |  |  | Assy |  |  |  |  |  |  |  |  |  |  |  |  |  |  |  |  |  |  |  |  |
| 11 | 2 | B42.00Q0Q.0011 | CVR M2 PVT LIGHTNING | M.2 DieCasting Module Plastic Cover |  | 1 | 1 |  | JPSeco NFrPP325m | Plastic | UNEEC |  |  |  |  |  |  |  |  |  |  |  |  |  |  |  |  |  |  |  |
| 12 | 2 | B42.00Q0J.0001 | LATCH ROTARY LIGHTNING PVT | LATCH_LOCKING_ADAPTER_V2 |  | 1 | 1 |  | JPSeco NFrPP325m | Plastic | UNEEC |  |  |  |  |  |  |  |  |  |  |  |  |  |  |  |  |  |  |  |
| 13 | 2 | 086.000H3.0545 | SCRW ROTARY SHOULDER LIGHTNING | LATCH SCREW M3 |  | 1 | 1 |  | Screw | purchase |  |  |  |  |  |  |  |  |  |  |  |  |  |  |  |  |  |  |  |  |
|  |  |  |  |  |  |  |  | 2 |  |  |  |  |  |  |  |  |  |  |  |  |  | V |  |  |  | V | V |  |  |  |
|  |  |  |  |  |  |  |  | 1 |  |  |  |  |  |  |  |  |  |  |  |  |  |  |  |  |  | V | V |  |  |  |
|  |  |  |  |  |  |  |  | 1 |  |  |  |  |  |  |  |  |  |  |  |  |  | V |  |  |  | V | V |  |  |  |
|  |  |  |  |  |  |  |  |  |  |  |  |  |  |  |  |  |  |  |  |  |  |  |  |  |  | V | V |  |  |  |
|  |  |  |  |  |  |  |  |  |  |  |  |  |  |  |  |  |  |  |  |  |  | V |  |  |  | V | V |  |  |  |
|  |  |  |  |  |  |  |  |  |  |  |  |  |  |  |  |  |  |  |  |  |  |  |  |  |  | V | V |  |  |  |
|  |  |  |  |  |  |  |  |  |  |  |  |  |  |  |  |  |  |  |  |  |  | V |  |  |  | V | V |  |  |  |
|  |  |  |  |  |  |  |  |  |  |  |  |  |  |  |  |  |  |  |  |  |  | V |  |  |  | V | V |  |  |  |
|  |  |  |  |  |  |  |  |  |  |  |  |  |  |  |  |  |  |  |  |  |  |  |  |  |  | V | V |  |  |  |
|  |  |  |  |  |  |  |  | 4 |  |  |  |  |  |  |  |  |  |  |  |  |  |  |  |  |  | V | V |  |  |  |
|  |  |  |  |  |  |  |  | 1 |  |  |  |  |  |  |  |  |  |  |  |  |  |  |  |  |  | V | V |  |  |  |
|  |  |  |  |  |  |  |  | 2 |  |  |  |  |  |  |  |  |  |  |  |  |  |  |  |  |  | V | V |  |  |  |
|  |  |  |  |  |  |  |  | 4 |  |  |  |  |  |  |  |  |  |  |  |  |  |  |  |  |  | V | V |  |  |  |
|  |  |  |  |  |  |  |  | 1 |  |  |  |  |  |  |  |  |  |  |  |  |  |  |  |  |  | V | V |  |  |  |
|  |  |  |  |  |  |  |  | 10 |  |  |  |  |  |  |  |  |  |  |  |  |  |  |  |  |  | V | V |  |  |  |
|  |  |  |  |  |  |  |  | 1 |  |  |  |  |  |  |  |  |  |  |  |  |  |  |  |  |  |  |  |  |  |  |
|  |  |  |  |  |  |  |  | 1 |  |  |  |  |  |  |  |  |  |  |  |  |  |  |  |  |  |  |  |  |  |  |
|  |  |  |  |  |  |  |  | 1 |  |  |  |  |  |  |  |  |  |  |  |  |  |  |  |  |  |  |  |  |  |  |
|  |  |  |  |  |  |  |  | 1 |  |  |  |  |  |  |  |  |  |  |  |  |  | v |  |  |  | V | V |  |  |  |
|  |  |  |  |  |  |  |  | 1 |  |  |  |  |  |  |  |  |  |  |  |  |  | v |  |  |  | V | V |  |  |  |
|  |  |  |  |  |  |  |  | 1 |  |  |  |  |  |  |  |  |  |  |  |  |  |  |  |  |  | V | V |  |  |  |
|  |  |  |  |  |  |  |  | 1 |  |  |  |  |  |  |  |  |  |  |  |  |  |  |  |  |  | V | V |  |  |  |
|  |  |  |  |  |  |  |  | 1 |  |  |  |  |  |  |  |  |  |  |  |  |  | v |  |  |  | V | V |  |  |  |
|  |  |  |  |  |  |  |  | 1 |  |  |  |  |  |  |  |  |  |  |  |  |  | v |  |  |  | V | V |  |  |  |
|  |  |  |  |  |  |  |  | 1 |  |  |  |  |  |  |  |  |  |  |  |  |  | v |  |  |  | V | V |  |  |  |
|  |  |  |  |  |  |  |  | 1 |  |  |  |  |  |  |  |  |  |  |  |  |  |  |  |  |  | V | V |  |  |  |
|  |  |  |  |  |  |  |  | 1 |  |  |  |  |  |  |  |  |  |  |  |  |  | v |  |  |  | V | V |  |  |  |
|  |  |  |  |  |  |  |  | 2 |  |  |  |  |  |  |  |  |  |  |  |  |  |  |  |  |  | V | V |  |  |  |
|  |  |  |  |  |  |  |  | 1 |  |  |  |  |  |  |  |  |  |  |  |  |  | v |  |  |  | V | V |  |  |  |
|  |  |  |  |  |  |  |  | 1 |  |  |  |  |  |  |  |  |  |  |  |  |  | v |  |  |  | V | V |  |  |  |
|  |  |  |  |  |  |  |  | 0 |  |  |  |  |  |  |  |  |  |  |  |  |  |  |  |  |  | V | V |  |  |  |
|  |  |  |  |  |  |  |  | 1 |  |  |  |  |  |  |  |  |  |  |  |  |  |  |  |  |  |  |  |  |  |  |
|  |  |  |  |  |  |  |  | 1 |  |  |  |  |  |  |  |  |  |  |  |  |  |  |  |  |  |  |  |  |  |  |
|  |  |  |  |  |  |  |  | 1 |  |  |  |  |  |  |  |  |  |  |  |  |  |  |  |  |  |  |  |  |  |  |
|  |  |  |  |  |  |  |  | 1 |  |  |  |  |  |  |  |  |  |  |  |  |  |  |  |  |  | V | V |  |  |  |
|  |  |  |  |  |  |  |  | 1 |  |  |  |  |  |  |  |  |  |  |  |  |  |  |  |  |  | V | V |  |  |  |
|  |  |  |  |  |  |  |  | 1 |  |  |  |  |  |  |  |  |  |  |  |  |  |  |  |  |  | V | V |  |  |  |
|  |  |  |  |  |  |  |  | 1 |  |  |  |  |  |  |  |  |  |  |  |  |  |  |  |  |  | V | V |  |  |  |
|  |  |  |  |  |  |  |  | 1 |  |  |  |  |  |  |  |  |  |  |  |  |  |  |  |  |  | V | V |  |  |  |
|  |  |  |  |  |  |  |  | 1 |  |  |  |  |  |  |  |  |  |  |  |  |  |  |  |  |  | V | V |  |  |  |
|  |  |  |  |  |  |  |  | 1 |  |  |  |  |  |  |  |  |  |  |  |  |  |  |  |  |  | V | V |  |  |  |
|  |  |  |  |  |  |  |  | 1 |  |  |  |  |  |  |  |  |  |  |  |  |  |  |  |  |  | V | V |  |  |  |
|  |  |  |  |  |  |  |  | 2 |  |  |  |  |  |  |  |  |  |  |  |  |  |  |  |  |  | V | V |  |  |  |
|  |  |  |  |  |  |  |  | 1 |  |  |  |  |  |  |  |  |  |  |  |  |  |  |  |  |  | V | V |  |  |  |
|  |  |  |  |  |  |  |  | 1 |  |  |  |  |  |  |  |  |  |  |  |  |  |  |  |  |  | V | V |  |  |  |
|  |  |  |  |  |  |  |  |  |  |  |  |  |  |  | Currency(USD) |  |  |  |  |  |  |  |  |  |  |  |  |  |  |  |
|  |  |  |  |  |  |  |  |  |  |  |  |  | Metal |  |  | 0 |  |  |  |  |  |  |  |  |  |  |  |  |  |  |
|  |  |  |  |  |  |  |  |  |  |  |  |  | Plastic(Fan duct) |  |  | 0 |  |  |  |  |  |  |  |  |  |  |  |  |  |  |
|  |  |  |  |  |  |  |  |  |  |  |  |  | Purchase |  |  | 0 |  |  |  |  |  |  |  |  |  |  |  |  |  |  |
|  |  |  |  |  |  |  |  |  |  |  |  |  | Tray (Q'ty:10) |  |  | 20.115122129578801 |  |  |  |  |  |  |  |  |  |  |  |  |  |  |
|  |  |  |  |  |  |  |  |  |  |  |  |  | Ass'y |  |  | #REF! |  |  |  |  |  |  |  |  |  |  |  |  |  |  |
|  |  |  |  |  |  |  |  |  |  |  |  |  | Packing |  |  | #REF! |  |  |  |  |  |  |  |  |  |  |  |  |  |  |
|  |  |  |  |  |  |  |  |  |  |  |  |  | Transportation |  |  | #REF! |  |  |  |  |  |  |  |  |  |  |  |  |  |  |
|  |  |  |  |  |  |  |  |  |  |  |  |  | Parts total |  |  | #REF! |  |  |  |  |  |  |  |  |  |  |  |  |  |  |
|  |  |  |  |  |  |  |  |  |  |  |  |  | New Tooling for Lyra(M) |  |  | 0 |  |  |  |  |  |  |  |  |  |  |  |  |  |  |
|  |  |  |  |  |  |  |  |  |  |  |  |  | New Tooling for Lyra(P) |  |  | 0 |  |  |  |  |  |  |  |  |  |  |  |  |  |  |
|  |  |  |  |  |  |  |  |  |  |  |  |  | Tooling modification for Lyra |  |  | 0 |  |  |  |  |  |  |  |  |  |  |  |  |  |  |
|  |  |  |  |  |  |  |  |  |  |  |  |  | Tooling Total |  |  | 0 |  |  |  |  |  |  |  |  |  |  |  |  |  |  |
